# S9S_MB_2U (Grand Teton) — schematic netlist excerpt (pin names and nets, part order shuffled) for the footprints in the layout excerpt that follows; sources: Cadence DE-HDL packaged netlist, KiCad conversion of 03242023_DA0F0TMBIJ0_F0T_Motherboard_J_brd_V01_OCP.brd

J69  PICOPROBE_BXA  DELTA-L 4.0 EMPTY  pkg TRIANG_LAUNCH_3PXB  page 308
  \1_p\  = DELTA_L_85_5INCH_TOP_DN
  \2_n\  = DELTA_L_85_5INCH_TOP_DP
  \3_g\  = DELTA_L_GND_1

(kicad_pcb
	(version 20260206)
	(generator "pcbnew")
	(generator_version "10.0")
	(general
		(thickness 1.6)
		(legacy_teardrops no)
	)
	(paper "A4")
	(title_block
		(title "03242023_DA0F0TMBIJ0_F0T_Motherboard_J_brd_V01_OCP.brd")
		(comment 1 "Grand Teton / footprints 603-603 of 6105")
	)
	(layers
		(0 "F.Cu" signal "TOP")
		(4 "In1.Cu" signal "GND")
		(6 "In2.Cu" signal "IN1")
		(8 "In3.Cu" signal "GND1")
		(10 "In4.Cu" signal "IN2")
		(12 "In5.Cu" signal "GND2")
		(14 "In6.Cu" signal "IN3")
		(16 "In7.Cu" signal "GND3")
		(18 "In8.Cu" signal "VCC")
		(20 "In9.Cu" signal "VCC1")
		(22 "In10.Cu" signal "GND4")
		(24 "In11.Cu" signal "IN4")
		(26 "In12.Cu" signal "GND5")
		(28 "In13.Cu" signal "IN5")
		(30 "In14.Cu" signal "GND6")
		(32 "In15.Cu" signal "IN6")
		(34 "In16.Cu" signal "GND7")
		(2 "B.Cu" signal "BOTTOM")
		(9 "F.Adhes" user "F.Adhesive")
		(11 "B.Adhes" user "B.Adhesive")
		(13 "F.Paste" user "Package Geometry/Pastemask Top")
		(15 "B.Paste" user "Package Geometry/Pastemask Bottom")
		(5 "F.SilkS" user "Ref Des/Silkscreen Top")
		(7 "B.SilkS" user "Ref Des/Silkscreen Bottom")
		(1 "F.Mask" user "Board Geometry/Soldermask Top")
		(3 "B.Mask" user "Board Geometry/Soldermask Bottom")
		(17 "Dwgs.User" user "User.Drawings")
		(19 "Cmts.User" user "User.Comments")
		(21 "Eco1.User" user "User.Eco1")
		(23 "Eco2.User" user "User.Eco2")
		(25 "Edge.Cuts" user "Board Geometry/Outline")
		(27 "Margin" user)
		(31 "F.CrtYd" user "Package Geometry/Place Bound Top")
		(29 "B.CrtYd" user "Package Geometry/Place Bound Bottom")
		(35 "F.Fab" user "Ref Des/Assembly Top")
		(33 "B.Fab" user "Ref Des/Assembly Bottom")
	)
	(footprint ""
		(layer "F.Cu")
		(at 339.298534 -4.696206)
		(property "Reference" "J69"
			(at -4.245864 1.140206 90)
			(unlocked yes)
			(layer "F.SilkS")
			(effects
				(font
					(size 0.7874 0.5842)
					(thickness 0.1524)
				)
				(justify left)
			)
		)
		(property "Value" ""
			(at 0 0 0)
			(layer "F.Fab")
			(effects
				(font
					(size 1.27 1.27)
				)
			)
		)
		(duplicate_pad_numbers_are_jumpers no)
		(fp_line
			(start -1.2192 -2.1082)
			(end 1.2192 -2.1082)
			(stroke
				(width 0.1524)
				(type default)
			)
			(layer "F.SilkS")
		)
		(fp_line
			(start -1.2192 2.1082)
			(end -1.2192 -2.1082)
			(stroke
				(width 0.1524)
				(type default)
			)
			(layer "F.SilkS")
		)
		(fp_line
			(start 1.2192 -2.1082)
			(end 1.2192 2.1082)
			(stroke
				(width 0.1524)
				(type default)
			)
			(layer "F.SilkS")
		)
		(fp_line
			(start 1.2192 2.1082)
			(end -1.2192 2.1082)
			(stroke
				(width 0.1524)
				(type default)
			)
			(layer "F.SilkS")
		)
		(pad "" np_thru_hole circle
			(at -2.8829 -1.27 270)
			(size 1.0414 1.0414)
			(drill 1.0414)
			(layers "*.Cu" "*.Mask")
			(clearance 0.381)
			(thermal_gap 0.381)
		)
		(pad "" np_thru_hole circle
			(at -2.8829 1.27 270)
			(size 1.0414 1.0414)
			(drill 1.0414)
			(layers "*.Cu" "*.Mask")
			(clearance 0.381)
			(thermal_gap 0.381)
		)
		(pad "" np_thru_hole circle
			(at 3.4671 -1.27 270)
			(size 1.0414 1.0414)
			(drill 1.0414)
			(layers "*.Cu" "*.Mask")
			(clearance 0.381)
			(thermal_gap 0.381)
		)
		(pad "" np_thru_hole circle
			(at 3.4671 1.27 270)
			(size 1.0414 1.0414)
			(drill 1.0414)
			(layers "*.Cu" "*.Mask")
			(clearance 0.381)
			(thermal_gap 0.381)
		)
		(pad "1" smd rect
			(at 0.8255 -0.249936 270)
			(size 0.3048 0.508)
			(layers "F.Cu" "F.Mask" "F.Paste")
			(net "DELTA_L_85_5INCH_TOP_DN")
		)
		(pad "2" smd rect
			(at 0.8255 0.249936 270)
			(size 0.3048 0.508)
			(layers "F.Cu" "F.Mask" "F.Paste")
			(net "DELTA_L_85_5INCH_TOP_DP")
		)
		(pad "3" smd circle
			(at 0 0)
			(size 0 0)
			(layers "F.Cu" "F.Mask" "F.Paste")
			(net "DELTA_L_GND_1")
		)
		(zone
			(layer "F.Cu")
			(hatch none 0.5)
			(connect_pads
				(clearance 0)
			)
			(min_thickness 0.25)
			(keepout
				(tracks not_allowed)
				(vias allowed)
				(pads allowed)
				(copperpour not_allowed)
				(footprints allowed)
			)
			(placement
				(enabled no)
				(sheetname "")
			)
			(fill
				(thermal_gap 0.5)
				(thermal_bridge_width 0.5)
				(island_removal_mode 0)
			)
			(polygon
				(pts
					(xy 340.416134 -5.244846) (xy 340.416134 -5.149342) (xy 339.819234 -5.149342) (xy 339.819234 -4.742942)
					(xy 340.416134 -4.742942) (xy 340.416134 -4.64947) (xy 339.819234 -4.64947) (xy 339.819234 -4.24307)
					(xy 340.416134 -4.24307) (xy 340.416134 -4.147566) (xy 339.717634 -4.147566) (xy 339.717634 -5.244846)
				)
			)
		)
		(zone
			(layers "F.Cu" "B.Cu" "In1.Cu" "In2.Cu" "In3.Cu" "In4.Cu" "In5.Cu" "In6.Cu"
				"In7.Cu" "In8.Cu" "In9.Cu" "In10.Cu" "In11.Cu" "In12.Cu" "In13.Cu" "In14.Cu"
				"In15.Cu" "In16.Cu"
			)
			(hatch none 0.5)
			(connect_pads
				(clearance 0)
			)
			(min_thickness 0.25)
			(keepout
				(tracks not_allowed)
				(vias allowed)
				(pads allowed)
				(copperpour not_allowed)
				(footprints allowed)
			)
			(placement
				(enabled no)
				(sheetname "")
			)
			(fill
				(thermal_gap 0.5)
				(thermal_bridge_width 0.5)
				(island_removal_mode 0)
			)
			(polygon
				(pts
					(arc
						(start 337.342734 -5.966206)
						(mid 335.488534 -5.966206)
						(end 337.342734 -5.966206)
					)
				)
			)
		)
		(zone
			(layers "F.Cu" "B.Cu" "In1.Cu" "In2.Cu" "In3.Cu" "In4.Cu" "In5.Cu" "In6.Cu"
				"In7.Cu" "In8.Cu" "In9.Cu" "In10.Cu" "In11.Cu" "In12.Cu" "In13.Cu" "In14.Cu"
				"In15.Cu" "In16.Cu"
			)
			(hatch none 0.5)
			(connect_pads
				(clearance 0)
			)
			(min_thickness 0.25)
			(keepout
				(tracks not_allowed)
				(vias allowed)
				(pads allowed)
				(copperpour not_allowed)
				(footprints allowed)
			)
			(placement
				(enabled no)
				(sheetname "")
			)
			(fill
				(thermal_gap 0.5)
				(thermal_bridge_width 0.5)
				(island_removal_mode 0)
			)
			(polygon
				(pts
					(arc
						(start 337.342734 -3.426206)
						(mid 335.488534 -3.426206)
						(end 337.342734 -3.426206)
					)
				)
			)
		)
		(zone
			(layers "F.Cu" "B.Cu" "In1.Cu" "In2.Cu" "In3.Cu" "In4.Cu" "In5.Cu" "In6.Cu"
				"In7.Cu" "In8.Cu" "In9.Cu" "In10.Cu" "In11.Cu" "In12.Cu" "In13.Cu" "In14.Cu"
				"In15.Cu" "In16.Cu"
			)
			(hatch none 0.5)
			(connect_pads
				(clearance 0)
			)
			(min_thickness 0.25)
			(keepout
				(tracks not_allowed)
				(vias allowed)
				(pads allowed)
				(copperpour not_allowed)
				(footprints allowed)
			)
			(placement
				(enabled no)
				(sheetname "")
			)
			(fill
				(thermal_gap 0.5)
				(thermal_bridge_width 0.5)
				(island_removal_mode 0)
			)
			(polygon
				(pts
					(arc
						(start 343.692734 -5.966206)
						(mid 341.838534 -5.966206)
						(end 343.692734 -5.966206)
					)
				)
			)
		)
		(zone
			(layers "F.Cu" "B.Cu" "In1.Cu" "In2.Cu" "In3.Cu" "In4.Cu" "In5.Cu" "In6.Cu"
				"In7.Cu" "In8.Cu" "In9.Cu" "In10.Cu" "In11.Cu" "In12.Cu" "In13.Cu" "In14.Cu"
				"In15.Cu" "In16.Cu"
			)
			(hatch none 0.5)
			(connect_pads
				(clearance 0)
			)
			(min_thickness 0.25)
			(keepout
				(tracks not_allowed)
				(vias allowed)
				(pads allowed)
				(copperpour not_allowed)
				(footprints allowed)
			)
			(placement
				(enabled no)
				(sheetname "")
			)
			(fill
				(thermal_gap 0.5)
				(thermal_bridge_width 0.5)
				(island_removal_mode 0)
			)
			(polygon
				(pts
					(arc
						(start 343.692734 -3.426206)
						(mid 341.838534 -3.426206)
						(end 343.692734 -3.426206)
					)
				)
			)
		)
	)
)
